(kicad_pcb
	(version 20260206)
	(generator "pcbnew")
	(generator_version "10.0")
	(general
		(thickness 1.6)
		(legacy_teardrops no)
	)
	(paper "A4")
	(title_block
		(title "04192023_DAF0TMB3IC0_F0TG_MB_C_brd_V02_OCP.brd")
		(comment 1 "Grand Teton / footprints 6454-6460 of 8354")
	)
	(layers
		(0 "F.Cu" signal "TOP")
		(4 "In1.Cu" signal "GND")
		(6 "In2.Cu" signal "IN1")
		(8 "In3.Cu" signal "GND1")
		(10 "In4.Cu" signal "IN2")
		(12 "In5.Cu" signal "GND2")
		(14 "In6.Cu" signal "IN3")
		(16 "In7.Cu" signal "GND3")
		(18 "In8.Cu" signal "VCC")
		(20 "In9.Cu" signal "VCC1")
		(22 "In10.Cu" signal "GND4")
		(24 "In11.Cu" signal "IN4")
		(26 "In12.Cu" signal "GND5")
		(28 "In13.Cu" signal "IN5")
		(30 "In14.Cu" signal "GND6")
		(32 "In15.Cu" signal "IN6")
		(34 "In16.Cu" signal "GND7")
		(2 "B.Cu" signal "BOTTOM")
		(9 "F.Adhes" user "F.Adhesive")
		(11 "B.Adhes" user "B.Adhesive")
		(13 "F.Paste" user "Package Geometry/Pastemask Top")
		(15 "B.Paste" user "Package Geometry/Pastemask Bottom")
		(5 "F.SilkS" user "Ref Des/Silkscreen Top")
		(7 "B.SilkS" user "Ref Des/Silkscreen Bottom")
		(1 "F.Mask" user "Board Geometry/Soldermask Top")
		(3 "B.Mask" user "Board Geometry/Soldermask Bottom")
		(17 "Dwgs.User" user "User.Drawings")
		(19 "Cmts.User" user "User.Comments")
		(21 "Eco1.User" user "User.Eco1")
		(23 "Eco2.User" user "User.Eco2")
		(25 "Edge.Cuts" user "Board Geometry/Outline")
		(27 "Margin" user)
		(31 "F.CrtYd" user "Package Geometry/Place Bound Top")
		(29 "B.CrtYd" user "Package Geometry/Place Bound Bottom")
		(35 "F.Fab" user "Ref Des/Assembly Top")
		(33 "B.Fab" user "Ref Des/Assembly Bottom")
	)
	(footprint ""
		(layer "B.Cu")
		(at 305.918362 -396.393162 -90)
		(property "Reference" "C543"
			(at 0 0 90)
			(layer "B.SilkS")
			(hide yes)
			(effects
				(font
					(size 1.27 1.27)
				)
				(justify mirror)
			)
		)
		(property "Value" ""
			(at 0 0 90)
			(layer "B.Fab")
			(effects
				(font
					(size 1.27 1.27)
				)
				(justify mirror)
			)
		)
		(duplicate_pad_numbers_are_jumpers no)
		(fp_line
			(start -0.299974 0.150114)
			(end 0.299974 0.150114)
			(stroke
				(width 0.1)
				(type default)
			)
			(layer "B.Fab")
		)
		(fp_line
			(start 0.299974 0.150114)
			(end 0.299974 -0.150114)
			(stroke
				(width 0.1)
				(type default)
			)
			(layer "B.Fab")
		)
		(fp_line
			(start -0.299974 -0.150114)
			(end -0.299974 0.150114)
			(stroke
				(width 0.1)
				(type default)
			)
			(layer "B.Fab")
		)
		(fp_line
			(start 0.299974 -0.150114)
			(end -0.299974 -0.150114)
			(stroke
				(width 0.1)
				(type default)
			)
			(layer "B.Fab")
		)
		(pad "1" smd rect
			(at 0.2667 0 90)
			(size 0.3048 0.381)
			(layers "B.Cu" "B.Mask" "B.Paste")
			(net "P0V9_CPU0_RT0_2A")
		)
		(pad "2" smd rect
			(at -0.2667 0 90)
			(size 0.3048 0.381)
			(layers "B.Cu" "B.Mask" "B.Paste")
			(net "GND")
		)
	)
	(footprint ""
		(layer "B.Cu")
		(at 295.478454 -190.94831 180)
		(property "Reference" "R292"
			(at 0 0 0)
			(layer "B.SilkS")
			(hide yes)
			(effects
				(font
					(size 1.27 1.27)
				)
				(justify mirror)
			)
		)
		(property "Value" ""
			(at 0 0 0)
			(layer "B.Fab")
			(effects
				(font
					(size 1.27 1.27)
				)
				(justify mirror)
			)
		)
		(duplicate_pad_numbers_are_jumpers no)
		(fp_line
			(start 0.7874 0.4064)
			(end 0.7874 -0.4064)
			(stroke
				(width 0.1524)
				(type default)
			)
			(layer "B.SilkS")
		)
		(fp_line
			(start 0.7874 -0.4064)
			(end -0.7874 -0.4064)
			(stroke
				(width 0.1524)
				(type default)
			)
			(layer "B.SilkS")
		)
		(fp_line
			(start -0.7874 0.4064)
			(end 0.7874 0.4064)
			(stroke
				(width 0.1524)
				(type default)
			)
			(layer "B.SilkS")
		)
		(fp_line
			(start -0.7874 -0.4064)
			(end -0.7874 0.4064)
			(stroke
				(width 0.1524)
				(type default)
			)
			(layer "B.SilkS")
		)
		(fp_line
			(start 0.67945 0.3048)
			(end 0.67945 -0.305054)
			(stroke
				(width 0.1)
				(type default)
			)
			(layer "B.Fab")
		)
		(fp_line
			(start 0.67945 -0.305054)
			(end 0.12065 -0.305054)
			(stroke
				(width 0.1)
				(type default)
			)
			(layer "B.Fab")
		)
		(fp_line
			(start 0.12065 0.3048)
			(end 0.67945 0.3048)
			(stroke
				(width 0.1)
				(type default)
			)
			(layer "B.Fab")
		)
		(fp_line
			(start 0.12065 0.2794)
			(end 0.12065 0.3048)
			(stroke
				(width 0.1)
				(type default)
			)
			(layer "B.Fab")
		)
		(fp_line
			(start 0.12065 -0.2794)
			(end -0.12065 -0.2794)
			(stroke
				(width 0.1)
				(type default)
			)
			(layer "B.Fab")
		)
		(fp_line
			(start 0.12065 -0.305054)
			(end 0.12065 -0.2794)
			(stroke
				(width 0.1)
				(type default)
			)
			(layer "B.Fab")
		)
		(fp_line
			(start -0.120396 0.3048)
			(end -0.120396 0.2794)
			(stroke
				(width 0.1)
				(type default)
			)
			(layer "B.Fab")
		)
		(fp_line
			(start -0.120396 0.2794)
			(end 0.12065 0.2794)
			(stroke
				(width 0.1)
				(type default)
			)
			(layer "B.Fab")
		)
		(fp_line
			(start -0.12065 -0.2794)
			(end -0.12065 -0.3048)
			(stroke
				(width 0.1)
				(type default)
			)
			(layer "B.Fab")
		)
		(fp_line
			(start -0.12065 -0.3048)
			(end -0.67945 -0.3048)
			(stroke
				(width 0.1)
				(type default)
			)
			(layer "B.Fab")
		)
		(fp_line
			(start -0.67945 0.3048)
			(end -0.120396 0.3048)
			(stroke
				(width 0.1)
				(type default)
			)
			(layer "B.Fab")
		)
		(fp_line
			(start -0.67945 -0.3048)
			(end -0.67945 0.3048)
			(stroke
				(width 0.1)
				(type default)
			)
			(layer "B.Fab")
		)
		(pad "1" smd circle
			(at 0.40005 0)
			(size 0 0)
			(layers "B.Cu" "B.Mask" "B.Paste")
			(net "PWRGD_CHB_CPU0_DIMM")
		)
		(pad "2" smd circle
			(at -0.40005 0)
			(size 0 0)
			(layers "B.Cu" "B.Mask" "B.Paste")
			(net "PWRGD_CHAF_CPU0")
		)
	)
	(footprint ""
		(layer "B.Cu")
		(at 233.013758 -224.397316 -90)
		(property "Reference" "C2"
			(at 0 0 90)
			(layer "B.SilkS")
			(hide yes)
			(effects
				(font
					(size 1.27 1.27)
				)
				(justify mirror)
			)
		)
		(property "Value" ""
			(at 0 0 90)
			(layer "B.Fab")
			(effects
				(font
					(size 1.27 1.27)
				)
				(justify mirror)
			)
		)
		(duplicate_pad_numbers_are_jumpers no)
		(fp_line
			(start -0.7874 0.4064)
			(end 0.7874 0.4064)
			(stroke
				(width 0.1524)
				(type default)
			)
			(layer "B.SilkS")
		)
		(fp_line
			(start 0.7874 0.4064)
			(end 0.7874 -0.4064)
			(stroke
				(width 0.1524)
				(type default)
			)
			(layer "B.SilkS")
		)
		(fp_line
			(start -0.7874 -0.4064)
			(end -0.7874 0.4064)
			(stroke
				(width 0.1524)
				(type default)
			)
			(layer "B.SilkS")
		)
		(fp_line
			(start 0.7874 -0.4064)
			(end -0.7874 -0.4064)
			(stroke
				(width 0.1524)
				(type default)
			)
			(layer "B.SilkS")
		)
		(fp_line
			(start -0.67945 0.3048)
			(end -0.120396 0.3048)
			(stroke
				(width 0.1)
				(type default)
			)
			(layer "B.Fab")
		)
		(fp_line
			(start -0.120396 0.3048)
			(end -0.120396 0.2794)
			(stroke
				(width 0.1)
				(type default)
			)
			(layer "B.Fab")
		)
		(fp_line
			(start 0.12065 0.3048)
			(end 0.67945 0.3048)
			(stroke
				(width 0.1)
				(type default)
			)
			(layer "B.Fab")
		)
		(fp_line
			(start 0.67945 0.3048)
			(end 0.67945 -0.305054)
			(stroke
				(width 0.1)
				(type default)
			)
			(layer "B.Fab")
		)
		(fp_line
			(start -0.120396 0.2794)
			(end 0.12065 0.2794)
			(stroke
				(width 0.1)
				(type default)
			)
			(layer "B.Fab")
		)
		(fp_line
			(start 0.12065 0.2794)
			(end 0.12065 0.3048)
			(stroke
				(width 0.1)
				(type default)
			)
			(layer "B.Fab")
		)
		(fp_line
			(start -0.12065 -0.2794)
			(end -0.12065 -0.3048)
			(stroke
				(width 0.1)
				(type default)
			)
			(layer "B.Fab")
		)
		(fp_line
			(start 0.12065 -0.2794)
			(end -0.12065 -0.2794)
			(stroke
				(width 0.1)
				(type default)
			)
			(layer "B.Fab")
		)
		(fp_line
			(start -0.67945 -0.3048)
			(end -0.67945 0.3048)
			(stroke
				(width 0.1)
				(type default)
			)
			(layer "B.Fab")
		)
		(fp_line
			(start -0.12065 -0.3048)
			(end -0.67945 -0.3048)
			(stroke
				(width 0.1)
				(type default)
			)
			(layer "B.Fab")
		)
		(fp_line
			(start 0.12065 -0.305054)
			(end 0.12065 -0.2794)
			(stroke
				(width 0.1)
				(type default)
			)
			(layer "B.Fab")
		)
		(fp_line
			(start 0.67945 -0.305054)
			(end 0.12065 -0.305054)
			(stroke
				(width 0.1)
				(type default)
			)
			(layer "B.Fab")
		)
		(pad "1" smd circle
			(at 0.40005 0 90)
			(size 0 0)
			(layers "B.Cu" "B.Mask" "B.Paste")
			(net "P3V3_AUX")
		)
		(pad "2" smd circle
			(at -0.40005 0 90)
			(size 0 0)
			(layers "B.Cu" "B.Mask" "B.Paste")
			(net "GND")
		)
	)
	(footprint ""
		(layer "B.Cu")
		(at 162.489388 -13.651738 180)
		(property "Reference" "R4508"
			(at 0 0 0)
			(layer "B.SilkS")
			(hide yes)
			(effects
				(font
					(size 1.27 1.27)
				)
				(justify mirror)
			)
		)
		(property "Value" ""
			(at 0 0 0)
			(layer "B.Fab")
			(effects
				(font
					(size 1.27 1.27)
				)
				(justify mirror)
			)
		)
		(duplicate_pad_numbers_are_jumpers no)
		(fp_line
			(start 0.7874 0.4064)
			(end 0.7874 -0.4064)
			(stroke
				(width 0.1524)
				(type default)
			)
			(layer "B.SilkS")
		)
		(fp_line
			(start 0.7874 -0.4064)
			(end -0.7874 -0.4064)
			(stroke
				(width 0.1524)
				(type default)
			)
			(layer "B.SilkS")
		)
		(fp_line
			(start -0.7874 0.4064)
			(end 0.7874 0.4064)
			(stroke
				(width 0.1524)
				(type default)
			)
			(layer "B.SilkS")
		)
		(fp_line
			(start -0.7874 -0.4064)
			(end -0.7874 0.4064)
			(stroke
				(width 0.1524)
				(type default)
			)
			(layer "B.SilkS")
		)
		(fp_line
			(start 0.67945 0.3048)
			(end 0.67945 -0.305054)
			(stroke
				(width 0.1)
				(type default)
			)
			(layer "B.Fab")
		)
		(fp_line
			(start 0.67945 -0.305054)
			(end 0.12065 -0.305054)
			(stroke
				(width 0.1)
				(type default)
			)
			(layer "B.Fab")
		)
		(fp_line
			(start 0.12065 0.3048)
			(end 0.67945 0.3048)
			(stroke
				(width 0.1)
				(type default)
			)
			(layer "B.Fab")
		)
		(fp_line
			(start 0.12065 0.2794)
			(end 0.12065 0.3048)
			(stroke
				(width 0.1)
				(type default)
			)
			(layer "B.Fab")
		)
		(fp_line
			(start 0.12065 -0.2794)
			(end -0.12065 -0.2794)
			(stroke
				(width 0.1)
				(type default)
			)
			(layer "B.Fab")
		)
		(fp_line
			(start 0.12065 -0.305054)
			(end 0.12065 -0.2794)
			(stroke
				(width 0.1)
				(type default)
			)
			(layer "B.Fab")
		)
		(fp_line
			(start -0.120396 0.3048)
			(end -0.120396 0.2794)
			(stroke
				(width 0.1)
				(type default)
			)
			(layer "B.Fab")
		)
		(fp_line
			(start -0.120396 0.2794)
			(end 0.12065 0.2794)
			(stroke
				(width 0.1)
				(type default)
			)
			(layer "B.Fab")
		)
		(fp_line
			(start -0.12065 -0.2794)
			(end -0.12065 -0.3048)
			(stroke
				(width 0.1)
				(type default)
			)
			(layer "B.Fab")
		)
		(fp_line
			(start -0.12065 -0.3048)
			(end -0.67945 -0.3048)
			(stroke
				(width 0.1)
				(type default)
			)
			(layer "B.Fab")
		)
		(fp_line
			(start -0.67945 0.3048)
			(end -0.120396 0.3048)
			(stroke
				(width 0.1)
				(type default)
			)
			(layer "B.Fab")
		)
		(fp_line
			(start -0.67945 -0.3048)
			(end -0.67945 0.3048)
			(stroke
				(width 0.1)
				(type default)
			)
			(layer "B.Fab")
		)
		(pad "1" smd circle
			(at 0.40005 0)
			(size 0 0)
			(layers "B.Cu" "B.Mask" "B.Paste")
			(net "SMB_1_PLD_3V3AUX_SCL")
		)
		(pad "2" smd circle
			(at -0.40005 0)
			(size 0 0)
			(layers "B.Cu" "B.Mask" "B.Paste")
			(net "SMB_1_PLD_3V3AUX_SCL_R3")
		)
	)
	(footprint ""
		(layer "B.Cu")
		(at 178.881532 -414.283144 180)
		(property "Reference" "C1769"
			(at 0 0 0)
			(layer "B.SilkS")
			(hide yes)
			(effects
				(font
					(size 1.27 1.27)
				)
				(justify mirror)
			)
		)
		(property "Value" ""
			(at 0 0 0)
			(layer "B.Fab")
			(effects
				(font
					(size 1.27 1.27)
				)
				(justify mirror)
			)
		)
		(duplicate_pad_numbers_are_jumpers no)
		(fp_line
			(start 0.7874 0.4064)
			(end 0.7874 -0.4064)
			(stroke
				(width 0.1524)
				(type default)
			)
			(layer "B.SilkS")
		)
		(fp_line
			(start 0.7874 -0.4064)
			(end -0.7874 -0.4064)
			(stroke
				(width 0.1524)
				(type default)
			)
			(layer "B.SilkS")
		)
		(fp_line
			(start -0.7874 0.4064)
			(end 0.7874 0.4064)
			(stroke
				(width 0.1524)
				(type default)
			)
			(layer "B.SilkS")
		)
		(fp_line
			(start -0.7874 -0.4064)
			(end -0.7874 0.4064)
			(stroke
				(width 0.1524)
				(type default)
			)
			(layer "B.SilkS")
		)
		(fp_line
			(start 0.67945 0.3048)
			(end 0.67945 -0.305054)
			(stroke
				(width 0.1)
				(type default)
			)
			(layer "B.Fab")
		)
		(fp_line
			(start 0.67945 -0.305054)
			(end 0.12065 -0.305054)
			(stroke
				(width 0.1)
				(type default)
			)
			(layer "B.Fab")
		)
		(fp_line
			(start 0.12065 0.3048)
			(end 0.67945 0.3048)
			(stroke
				(width 0.1)
				(type default)
			)
			(layer "B.Fab")
		)
		(fp_line
			(start 0.12065 0.2794)
			(end 0.12065 0.3048)
			(stroke
				(width 0.1)
				(type default)
			)
			(layer "B.Fab")
		)
		(fp_line
			(start 0.12065 -0.2794)
			(end -0.12065 -0.2794)
			(stroke
				(width 0.1)
				(type default)
			)
			(layer "B.Fab")
		)
		(fp_line
			(start 0.12065 -0.305054)
			(end 0.12065 -0.2794)
			(stroke
				(width 0.1)
				(type default)
			)
			(layer "B.Fab")
		)
		(fp_line
			(start -0.120396 0.3048)
			(end -0.120396 0.2794)
			(stroke
				(width 0.1)
				(type default)
			)
			(layer "B.Fab")
		)
		(fp_line
			(start -0.120396 0.2794)
			(end 0.12065 0.2794)
			(stroke
				(width 0.1)
				(type default)
			)
			(layer "B.Fab")
		)
		(fp_line
			(start -0.12065 -0.2794)
			(end -0.12065 -0.3048)
			(stroke
				(width 0.1)
				(type default)
			)
			(layer "B.Fab")
		)
		(fp_line
			(start -0.12065 -0.3048)
			(end -0.67945 -0.3048)
			(stroke
				(width 0.1)
				(type default)
			)
			(layer "B.Fab")
		)
		(fp_line
			(start -0.67945 0.3048)
			(end -0.120396 0.3048)
			(stroke
				(width 0.1)
				(type default)
			)
			(layer "B.Fab")
		)
		(fp_line
			(start -0.67945 -0.3048)
			(end -0.67945 0.3048)
			(stroke
				(width 0.1)
				(type default)
			)
			(layer "B.Fab")
		)
		(pad "1" smd circle
			(at 0.40005 0)
			(size 0 0)
			(layers "B.Cu" "B.Mask" "B.Paste")
			(net "P3V3_AUX")
		)
		(pad "2" smd circle
			(at -0.40005 0)
			(size 0 0)
			(layers "B.Cu" "B.Mask" "B.Paste")
			(net "GND")
		)
	)
	(footprint ""
		(layer "B.Cu")
		(at 233.807 -338.582 180)
		(property "Reference" "R1025"
			(at 0 0 0)
			(layer "B.SilkS")
			(hide yes)
			(effects
				(font
					(size 1.27 1.27)
				)
				(justify mirror)
			)
		)
		(property "Value" ""
			(at 0 0 0)
			(layer "B.Fab")
			(effects
				(font
					(size 1.27 1.27)
				)
				(justify mirror)
			)
		)
		(duplicate_pad_numbers_are_jumpers no)
		(fp_line
			(start 0.32512 0.175006)
			(end 0.32512 -0.175006)
			(stroke
				(width 0.1)
				(type default)
			)
			(layer "B.Fab")
		)
		(fp_line
			(start 0.32512 -0.175006)
			(end -0.32512 -0.175006)
			(stroke
				(width 0.1)
				(type default)
			)
			(layer "B.Fab")
		)
		(fp_line
			(start -0.32512 0.175006)
			(end 0.32512 0.175006)
			(stroke
				(width 0.1)
				(type default)
			)
			(layer "B.Fab")
		)
		(fp_line
			(start -0.32512 -0.175006)
			(end -0.32512 0.175006)
			(stroke
				(width 0.1)
				(type default)
			)
			(layer "B.Fab")
		)
		(pad "1" smd rect
			(at 0.2667 0)
			(size 0.3048 0.381)
			(layers "B.Cu" "B.Mask" "B.Paste")
			(net "SMB_RT_CPU0_P1_R_SCL")
		)
		(pad "2" smd rect
			(at -0.2667 0 180)
			(size 0.3048 0.381)
			(layers "B.Cu" "B.Mask" "B.Paste")
			(net "SMB_RT_CPU0_P1_R2_SCL")
		)
	)
	(footprint ""
		(layer "B.Cu")
		(at 104.561386 -266.005564)
		(property "Reference" "C2261"
			(at 0 0 0)
			(layer "B.SilkS")
			(hide yes)
			(effects
				(font
					(size 1.27 1.27)
				)
				(justify mirror)
			)
		)
		(property "Value" ""
			(at 0 0 0)
			(layer "B.Fab")
			(effects
				(font
					(size 1.27 1.27)
				)
				(justify mirror)
			)
		)
		(duplicate_pad_numbers_are_jumpers no)
		(fp_line
			(start -0.7874 -0.4064)
			(end -0.7874 0.4064)
			(stroke
				(width 0.1524)
				(type default)
			)
			(layer "B.SilkS")
		)
		(fp_line
			(start -0.7874 0.4064)
			(end 0.7874 0.4064)
			(stroke
				(width 0.1524)
				(type default)
			)
			(layer "B.SilkS")
		)
		(fp_line
			(start 0.7874 -0.4064)
			(end -0.7874 -0.4064)
			(stroke
				(width 0.1524)
				(type default)
			)
			(layer "B.SilkS")
		)
		(fp_line
			(start 0.7874 0.4064)
			(end 0.7874 -0.4064)
			(stroke
				(width 0.1524)
				(type default)
			)
			(layer "B.SilkS")
		)
		(fp_line
			(start -0.67945 -0.3048)
			(end -0.67945 0.3048)
			(stroke
				(width 0.1)
				(type default)
			)
			(layer "B.Fab")
		)
		(fp_line
			(start -0.67945 0.3048)
			(end -0.120396 0.3048)
			(stroke
				(width 0.1)
				(type default)
			)
			(layer "B.Fab")
		)
		(fp_line
			(start -0.12065 -0.3048)
			(end -0.67945 -0.3048)
			(stroke
				(width 0.1)
				(type default)
			)
			(layer "B.Fab")
		)
		(fp_line
			(start -0.12065 -0.2794)
			(end -0.12065 -0.3048)
			(stroke
				(width 0.1)
				(type default)
			)
			(layer "B.Fab")
		)
		(fp_line
			(start -0.120396 0.2794)
			(end 0.12065 0.2794)
			(stroke
				(width 0.1)
				(type default)
			)
			(layer "B.Fab")
		)
		(fp_line
			(start -0.120396 0.3048)
			(end -0.120396 0.2794)
			(stroke
				(width 0.1)
				(type default)
			)
			(layer "B.Fab")
		)
		(fp_line
			(start 0.12065 -0.305054)
			(end 0.12065 -0.2794)
			(stroke
				(width 0.1)
				(type default)
			)
			(layer "B.Fab")
		)
		(fp_line
			(start 0.12065 -0.2794)
			(end -0.12065 -0.2794)
			(stroke
				(width 0.1)
				(type default)
			)
			(layer "B.Fab")
		)
		(fp_line
			(start 0.12065 0.2794)
			(end 0.12065 0.3048)
			(stroke
				(width 0.1)
				(type default)
			)
			(layer "B.Fab")
		)
		(fp_line
			(start 0.12065 0.3048)
			(end 0.67945 0.3048)
			(stroke
				(width 0.1)
				(type default)
			)
			(layer "B.Fab")
		)
		(fp_line
			(start 0.67945 -0.305054)
			(end 0.12065 -0.305054)
			(stroke
				(width 0.1)
				(type default)
			)
			(layer "B.Fab")
		)
		(fp_line
			(start 0.67945 0.3048)
			(end 0.67945 -0.305054)
			(stroke
				(width 0.1)
				(type default)
			)
			(layer "B.Fab")
		)
		(pad "1" smd circle
			(at 0.40005 0 180)
			(size 0 0)
			(layers "B.Cu" "B.Mask" "B.Paste")
			(net "PVDD11_S3_P1")
		)
		(pad "2" smd circle
			(at -0.40005 0 180)
			(size 0 0)
			(layers "B.Cu" "B.Mask" "B.Paste")
			(net "GND")
		)
	)
)
